(kicad_pcb
	(version 20260206)
	(generator "pcbnew")
	(generator_version "10.0")
	(general
		(thickness 1.6)
		(legacy_teardrops no)
	)
	(paper "A4")
	(title_block
		(title "Bryce Canyon_F.DPB_16315-1-OCP.brd")
		(comment 1 "Bryce Canyon / footprints 2080-2087 of 2223")
	)
	(layers
		(0 "F.Cu" signal "TOP")
		(4 "In1.Cu" signal "L2GND")
		(6 "In2.Cu" signal "L3")
		(8 "In3.Cu" signal "L4GND")
		(10 "In4.Cu" signal "L5")
		(12 "In5.Cu" signal "L6VCC")
		(14 "In6.Cu" signal "L7VCC")
		(16 "In7.Cu" signal "L8")
		(18 "In8.Cu" signal "L9GND")
		(20 "In9.Cu" signal "L10")
		(22 "In10.Cu" signal "L11GND")
		(2 "B.Cu" signal "BOTTOM")
		(9 "F.Adhes" user "F.Adhesive")
		(11 "B.Adhes" user "B.Adhesive")
		(13 "F.Paste" user "Package Geometry/Pastemask Top")
		(15 "B.Paste" user "Package Geometry/Pastemask Bottom")
		(5 "F.SilkS" user "Ref Des/Silkscreen Top")
		(7 "B.SilkS" user "Ref Des/Silkscreen Bottom")
		(1 "F.Mask" user "Board Geometry/Soldermask Top")
		(3 "B.Mask" user "Board Geometry/Soldermask Bottom")
		(17 "Dwgs.User" user "User.Drawings")
		(19 "Cmts.User" user "User.Comments")
		(21 "Eco1.User" user "User.Eco1")
		(23 "Eco2.User" user "User.Eco2")
		(25 "Edge.Cuts" user "Board Geometry/Outline")
		(27 "Margin" user)
		(31 "F.CrtYd" user "Package Geometry/Place Bound Top")
		(29 "B.CrtYd" user "Package Geometry/Place Bound Bottom")
		(35 "F.Fab" user "Ref Des/Assembly Top")
		(33 "B.Fab" user "Ref Des/Assembly Bottom")
	)
	(footprint ""
		(layer "B.Cu")
		(at 480.949 -230.505)
		(property "Reference" "C668"
			(at 0 0 0)
			(layer "B.SilkS")
			(hide yes)
			(effects
				(font
					(size 1.27 1.27)
				)
				(justify mirror)
			)
		)
		(property "Value" "SC68P50V2JN-2-GP"
			(at -1.1811 -2.7051 0)
			(unlocked yes)
			(layer "B.Fab")
			(hide yes)
			(effects
				(font
					(size 1.016 1.016)
					(thickness 0.1524)
				)
				(justify mirror)
			)
		)
		(property "Device Type" "C402H22"
			(at -1.1811 -4.2291 0)
			(unlocked yes)
			(layer "B.Fab")
			(hide yes)
			(effects
				(font
					(size 1.016 1.016)
					(thickness 0.1524)
				)
				(justify mirror)
			)
		)
		(duplicate_pad_numbers_are_jumpers no)
		(fp_rect
			(start 0.4318 0.9525)
			(end -0.4318 -0.9525)
			(stroke
				(width 0)
				(type default)
			)
			(fill no)
			(layer "B.CrtYd")
		)
		(fp_rect
			(start 0.4318 0.9525)
			(end -0.4318 -0.9525)
			(stroke
				(width 0)
				(type default)
			)
			(fill no)
			(layer "B.Fab")
		)
		(pad "1" smd custom
			(at 0 -0.4445 180)
			(size 0.1524 0.1524)
			(layers "B.Cu" "B.Mask" "B.Paste")
			(net "P5V_D_VFB")
			(options
				(clearance outline)
				(anchor circle)
			)
			(primitives
				(gr_poly
					(pts
						(arc
							(start 0.3048 0.2032)
							(mid 0.275042 0.275042)
							(end 0.2032 0.3048)
						)
						(arc
							(start -0.2032 0.3048)
							(mid -0.275042 0.275042)
							(end -0.3048 0.2032)
						)
						(arc
							(start -0.3048 -0.2032)
							(mid -0.275042 -0.275042)
							(end -0.2032 -0.3048)
						)
						(arc
							(start 0.2032 -0.3048)
							(mid 0.275042 -0.275042)
							(end 0.3048 -0.2032)
						)
					)
					(width 0)
					(fill yes)
				)
			)
		)
		(pad "2" smd custom
			(at 0 0.4445 180)
			(size 0.1524 0.1524)
			(layers "B.Cu" "B.Mask" "B.Paste")
			(net "P5V_D_VFB_R")
			(options
				(clearance outline)
				(anchor circle)
			)
			(primitives
				(gr_poly
					(pts
						(arc
							(start 0.3048 0.2032)
							(mid 0.275042 0.275042)
							(end 0.2032 0.3048)
						)
						(arc
							(start -0.2032 0.3048)
							(mid -0.275042 0.275042)
							(end -0.3048 0.2032)
						)
						(arc
							(start -0.3048 -0.2032)
							(mid -0.275042 -0.275042)
							(end -0.2032 -0.3048)
						)
						(arc
							(start 0.2032 -0.3048)
							(mid 0.275042 -0.275042)
							(end 0.3048 -0.2032)
						)
					)
					(width 0)
					(fill yes)
				)
			)
		)
	)
	(footprint ""
		(layer "B.Cu")
		(at 476.572834 -238.700564)
		(property "Reference" "C659"
			(at 0 0 0)
			(layer "B.SilkS")
			(hide yes)
			(effects
				(font
					(size 1.27 1.27)
				)
				(justify mirror)
			)
		)
		(property "Value" "SC1U16V3KX-5GP"
			(at 0 -2.8194 0)
			(unlocked yes)
			(layer "B.Fab")
			(hide yes)
			(effects
				(font
					(size 1.016 1.016)
					(thickness 0.1524)
				)
				(justify mirror)
			)
		)
		(property "Device Type" "C603H36"
			(at 0 -4.3434 0)
			(unlocked yes)
			(layer "B.Fab")
			(hide yes)
			(effects
				(font
					(size 1.016 1.016)
					(thickness 0.1524)
				)
				(justify mirror)
			)
		)
		(duplicate_pad_numbers_are_jumpers no)
		(fp_line
			(start -0.508 0)
			(end 0.508 0)
			(stroke
				(width 0.2032)
				(type default)
			)
			(layer "B.SilkS")
		)
		(fp_rect
			(start 0.5842 1.3335)
			(end -0.5842 -1.3335)
			(stroke
				(width 0)
				(type default)
			)
			(fill no)
			(layer "B.CrtYd")
		)
		(fp_rect
			(start 0.5842 1.3335)
			(end -0.5842 -1.3335)
			(stroke
				(width 0)
				(type default)
			)
			(fill no)
			(layer "B.Fab")
		)
		(pad "1" smd custom
			(at 0 -0.762 180)
			(size 0.2159 0.2159)
			(layers "B.Cu" "B.Mask" "B.Paste")
			(net "GND")
			(options
				(clearance outline)
				(anchor circle)
			)
			(primitives
				(gr_poly
					(pts
						(arc
							(start -0.3302 0.4318)
							(mid -0.402042 0.402042)
							(end -0.4318 0.3302)
						)
						(arc
							(start -0.4318 -0.3302)
							(mid -0.402042 -0.402042)
							(end -0.3302 -0.4318)
						)
						(arc
							(start 0.3302 -0.4318)
							(mid 0.402042 -0.402042)
							(end 0.4318 -0.3302)
						)
						(arc
							(start 0.4318 0.3302)
							(mid 0.402042 0.402042)
							(end 0.3302 0.4318)
						)
					)
					(width 0)
					(fill yes)
				)
			)
		)
		(pad "2" smd custom
			(at 0 0.762 180)
			(size 0.2159 0.2159)
			(layers "B.Cu" "B.Mask" "B.Paste")
			(net "P5V_D_VREG")
			(options
				(clearance outline)
				(anchor circle)
			)
			(primitives
				(gr_poly
					(pts
						(arc
							(start -0.3302 0.4318)
							(mid -0.402042 0.402042)
							(end -0.4318 0.3302)
						)
						(arc
							(start -0.4318 -0.3302)
							(mid -0.402042 -0.402042)
							(end -0.3302 -0.4318)
						)
						(arc
							(start 0.3302 -0.4318)
							(mid 0.402042 -0.402042)
							(end 0.4318 -0.3302)
						)
						(arc
							(start 0.4318 0.3302)
							(mid 0.402042 0.402042)
							(end 0.3302 0.4318)
						)
					)
					(width 0)
					(fill yes)
				)
			)
		)
	)
	(footprint ""
		(layer "B.Cu")
		(at 445.9732 -256.3622)
		(property "Reference" "PG15"
			(at 0 0 0)
			(layer "B.SilkS")
			(hide yes)
			(effects
				(font
					(size 1.27 1.27)
				)
				(justify mirror)
			)
		)
		(property "Value" "COPPER-CLOSE-GP-U"
			(at -0.0762 -2.8702 0)
			(unlocked yes)
			(layer "B.Fab")
			(hide yes)
			(effects
				(font
					(size 1.016 1.016)
					(thickness 0.1524)
				)
				(justify mirror)
			)
		)
		(property "Device Type" "CON2C-U"
			(at -0.0762 -4.3942 0)
			(unlocked yes)
			(layer "B.Fab")
			(hide yes)
			(effects
				(font
					(size 1.016 1.016)
					(thickness 0.1524)
				)
				(justify mirror)
			)
		)
		(duplicate_pad_numbers_are_jumpers no)
		(fp_rect
			(start 0.9398 0.9652)
			(end -0.9398 -0.9652)
			(stroke
				(width 0)
				(type default)
			)
			(fill no)
			(layer "B.CrtYd")
		)
		(fp_rect
			(start 0.9398 0.9652)
			(end -0.9398 -0.9652)
			(stroke
				(width 0)
				(type default)
			)
			(fill no)
			(layer "B.Fab")
		)
		(pad "1" smd custom
			(at 0 -0.5334 180)
			(size 0.17145 0.17145)
			(layers "B.Cu" "B.Mask" "B.Paste")
			(net "AGND_P5V_C")
			(options
				(clearance outline)
				(anchor circle)
			)
			(primitives
				(gr_poly
					(pts
						(xy -0.127 -0.3429) (xy -0.127 -0.1651) (xy -0.635 0.3429) (xy 0.635 0.3429) (xy 0.127 -0.1651)
						(xy 0.127 -0.3429)
					)
					(width 0)
					(fill yes)
				)
			)
		)
		(pad "2" smd custom
			(at 0 0.5334 180)
			(size 0.17145 0.17145)
			(layers "B.Cu" "B.Mask" "B.Paste")
			(net "GND")
			(options
				(clearance outline)
				(anchor circle)
			)
			(primitives
				(gr_poly
					(pts
						(xy -0.635 -0.3429) (xy -0.127 0.1651) (xy -0.127 0.3429) (xy 0.127 0.3429) (xy 0.127 0.1651)
						(xy 0.635 -0.3429)
					)
					(width 0)
					(fill yes)
				)
			)
		)
	)
	(footprint ""
		(layer "B.Cu")
		(at 483.449884 -204.199998 180)
		(property "Reference" "NUT2"
			(at 0 0 0)
			(layer "B.SilkS")
			(hide yes)
			(effects
				(font
					(size 1.27 1.27)
				)
				(justify mirror)
			)
		)
		(property "Value" "STF256R168H278-GP"
			(at 4.826 0.0508 180)
			(unlocked yes)
			(layer "B.Fab")
			(hide yes)
			(effects
				(font
					(size 1.016 1.016)
					(thickness 0.1524)
				)
				(justify mirror)
			)
		)
		(property "Device Type" "STF256R168H278"
			(at 4.826 -1.4732 180)
			(unlocked yes)
			(layer "B.Fab")
			(hide yes)
			(effects
				(font
					(size 1.016 1.016)
					(thickness 0.1524)
				)
				(justify mirror)
			)
		)
		(duplicate_pad_numbers_are_jumpers no)
		(fp_circle
			(center 0 0)
			(end -3.6068 0)
			(stroke
				(width 0.3048)
				(type default)
			)
			(fill no)
			(layer "B.SilkS")
		)
		(fp_poly
			(pts
				(arc
					(start -2.5019 0)
					(mid 2.5019 0)
					(end -2.5019 0)
				)
			)
			(stroke
				(width 0)
				(type default)
			)
			(fill no)
			(layer "B.CrtYd")
		)
		(fp_poly
			(pts
				(arc
					(start -3.7592 0.00635)
					(mid 3.759205 0)
					(end -3.7592 -0.00635)
				)
				(arc
					(start -2.5019 -0.00635)
					(mid 2.501908 0)
					(end -2.5019 0.00635)
				)
			)
			(stroke
				(width 0)
				(type default)
			)
			(fill no)
			(layer "B.CrtYd")
		)
		(fp_poly
			(pts
				(arc
					(start -3.7592 0)
					(mid 3.7592 0)
					(end -3.7592 0)
				)
			)
			(stroke
				(width 0)
				(type default)
			)
			(fill no)
			(layer "F.CrtYd")
		)
		(fp_poly
			(pts
				(arc
					(start -3.7592 0)
					(mid 3.7592 0)
					(end -3.7592 0)
				)
			)
			(stroke
				(width 0)
				(type default)
			)
			(fill no)
			(layer "B.Fab")
		)
		(fp_poly
			(pts
				(arc
					(start -3.7592 0)
					(mid 3.7592 0)
					(end -3.7592 0)
				)
			)
			(stroke
				(width 0)
				(type default)
			)
			(fill no)
			(layer "F.Fab")
		)
		(pad "1" thru_hole circle
			(at 0 0)
			(size 6.5024 6.5024)
			(drill 4.2672)
			(layers "*.Cu" "*.Mask")
			(remove_unused_layers no)
			(net "Net_14")
			(clearance -0.6096)
			(padstack
				(mode front_inner_back)
				(layer "Inner"
					(shape circle)
					(size 4.6736 4.6736)
					(clearance 0.3048)
				)
				(layer "B.Cu"
					(shape circle)
					(size 6.5024 6.5024)
					(thermal_gap 0.3048)
					(clearance -0.6096)
				)
			)
		)
	)
	(footprint ""
		(layer "B.Cu")
		(at 189.377828 -236.296708 90)
		(property "Reference" "C683"
			(at 0 0 90)
			(layer "B.SilkS")
			(hide yes)
			(effects
				(font
					(size 1.27 1.27)
				)
				(justify mirror)
			)
		)
		(property "Value" "SC10U6D3V5KX-4GP"
			(at 0.0762 -6.1214 90)
			(unlocked yes)
			(layer "B.Fab")
			(hide yes)
			(effects
				(font
					(size 1.016 1.016)
					(thickness 0.1524)
				)
				(justify mirror)
			)
		)
		(property "Device Type" "C805H58"
			(at 0.0762 -8.1534 90)
			(unlocked yes)
			(layer "B.Fab")
			(hide yes)
			(effects
				(font
					(size 1.016 1.016)
					(thickness 0.1524)
				)
				(justify mirror)
			)
		)
		(duplicate_pad_numbers_are_jumpers no)
		(fp_line
			(start -0.635 0)
			(end 0.635 0)
			(stroke
				(width 0.508)
				(type default)
			)
			(layer "B.SilkS")
		)
		(fp_rect
			(start 0.9652 1.778)
			(end -0.9652 -1.778)
			(stroke
				(width 0)
				(type default)
			)
			(fill no)
			(layer "B.CrtYd")
		)
		(fp_poly
			(pts
				(xy 0.9652 -1.778) (xy -0.9652 -1.778) (xy -0.9652 1.778) (xy 0.9652 1.778)
			)
			(stroke
				(width 0)
				(type default)
			)
			(fill no)
			(layer "B.Fab")
		)
		(pad "1" smd rect
			(at 0 -0.9652 270)
			(size 1.397 1.143)
			(layers "B.Cu" "B.Mask" "B.Paste")
			(net "P3V3_STBY_A")
		)
		(pad "2" smd rect
			(at 0 0.9652 270)
			(size 1.397 1.143)
			(layers "B.Cu" "B.Mask" "B.Paste")
			(net "GND")
		)
	)
	(footprint ""
		(layer "B.Cu")
		(at 347.000068 -164.200078 180)
		(property "Reference" "NUT5"
			(at 0 0 0)
			(layer "B.SilkS")
			(hide yes)
			(effects
				(font
					(size 1.27 1.27)
				)
				(justify mirror)
			)
		)
		(property "Value" "STF256R168H278-GP"
			(at 4.826 0.0508 180)
			(unlocked yes)
			(layer "B.Fab")
			(hide yes)
			(effects
				(font
					(size 1.016 1.016)
					(thickness 0.1524)
				)
				(justify mirror)
			)
		)
		(property "Device Type" "STF256R168H278"
			(at 4.826 -1.4732 180)
			(unlocked yes)
			(layer "B.Fab")
			(hide yes)
			(effects
				(font
					(size 1.016 1.016)
					(thickness 0.1524)
				)
				(justify mirror)
			)
		)
		(duplicate_pad_numbers_are_jumpers no)
		(fp_circle
			(center 0 0)
			(end -3.6068 0)
			(stroke
				(width 0.3048)
				(type default)
			)
			(fill no)
			(layer "B.SilkS")
		)
		(fp_poly
			(pts
				(arc
					(start -2.5019 0)
					(mid 2.5019 0)
					(end -2.5019 0)
				)
			)
			(stroke
				(width 0)
				(type default)
			)
			(fill no)
			(layer "B.CrtYd")
		)
		(fp_poly
			(pts
				(arc
					(start -3.7592 0.00635)
					(mid 3.759205 0)
					(end -3.7592 -0.00635)
				)
				(arc
					(start -2.5019 -0.00635)
					(mid 2.501908 0)
					(end -2.5019 0.00635)
				)
			)
			(stroke
				(width 0)
				(type default)
			)
			(fill no)
			(layer "B.CrtYd")
		)
		(fp_poly
			(pts
				(arc
					(start -3.7592 0)
					(mid 3.7592 0)
					(end -3.7592 0)
				)
			)
			(stroke
				(width 0)
				(type default)
			)
			(fill no)
			(layer "F.CrtYd")
		)
		(fp_poly
			(pts
				(arc
					(start -3.7592 0)
					(mid 3.7592 0)
					(end -3.7592 0)
				)
			)
			(stroke
				(width 0)
				(type default)
			)
			(fill no)
			(layer "B.Fab")
		)
		(fp_poly
			(pts
				(arc
					(start -3.7592 0)
					(mid 3.7592 0)
					(end -3.7592 0)
				)
			)
			(stroke
				(width 0)
				(type default)
			)
			(fill no)
			(layer "F.Fab")
		)
		(pad "1" thru_hole circle
			(at 0 0)
			(size 6.5024 6.5024)
			(drill 4.2672)
			(layers "*.Cu" "*.Mask")
			(remove_unused_layers no)
			(net "Net_11")
			(clearance -0.6096)
			(padstack
				(mode front_inner_back)
				(layer "Inner"
					(shape circle)
					(size 4.6736 4.6736)
					(clearance 0.3048)
				)
				(layer "B.Cu"
					(shape circle)
					(size 6.5024 6.5024)
					(thermal_gap 0.3048)
					(clearance -0.6096)
				)
			)
		)
	)
	(footprint ""
		(layer "B.Cu")
		(at 52.1716 -252.1966 180)
		(property "Reference" "C613"
			(at 0 0 0)
			(layer "B.SilkS")
			(hide yes)
			(effects
				(font
					(size 1.27 1.27)
				)
				(justify mirror)
			)
		)
		(property "Value" "SC10U16V5KX-7-GP-U"
			(at 0.0762 -6.1214 180)
			(unlocked yes)
			(layer "B.Fab")
			(hide yes)
			(effects
				(font
					(size 1.016 1.016)
					(thickness 0.1524)
				)
				(justify mirror)
			)
		)
		(property "Device Type" "C805H58"
			(at 0.0762 -8.1534 180)
			(unlocked yes)
			(layer "B.Fab")
			(hide yes)
			(effects
				(font
					(size 1.016 1.016)
					(thickness 0.1524)
				)
				(justify mirror)
			)
		)
		(duplicate_pad_numbers_are_jumpers no)
		(fp_line
			(start -0.635 0)
			(end 0.635 0)
			(stroke
				(width 0.508)
				(type default)
			)
			(layer "B.SilkS")
		)
		(fp_rect
			(start 0.9652 1.778)
			(end -0.9652 -1.778)
			(stroke
				(width 0)
				(type default)
			)
			(fill no)
			(layer "B.CrtYd")
		)
		(fp_poly
			(pts
				(xy 0.9652 -1.778) (xy -0.9652 -1.778) (xy -0.9652 1.778) (xy 0.9652 1.778)
			)
			(stroke
				(width 0)
				(type default)
			)
			(fill no)
			(layer "B.Fab")
		)
		(pad "1" smd rect
			(at 0 -0.9652)
			(size 1.397 1.143)
			(layers "B.Cu" "B.Mask" "B.Paste")
			(net "P5V_A_1")
		)
		(pad "2" smd rect
			(at 0 0.9652)
			(size 1.397 1.143)
			(layers "B.Cu" "B.Mask" "B.Paste")
			(net "GND")
		)
	)
	(footprint ""
		(layer "B.Cu")
		(at 48.6156 -253.9492 180)
		(property "Reference" "TC9"
			(at 0 0 0)
			(layer "B.SilkS")
			(hide yes)
			(effects
				(font
					(size 1.27 1.27)
				)
				(justify mirror)
			)
		)
		(property "Value" "ST220U10VDM-LGP"
			(at 0 -9.6012 180)
			(unlocked yes)
			(layer "B.Fab")
			(hide yes)
			(effects
				(font
					(size 1.016 1.016)
					(thickness 0.1524)
				)
				(justify mirror)
			)
		)
		(property "Device Type" "CT7343H119"
			(at 0 -11.1252 180)
			(unlocked yes)
			(layer "B.Fab")
			(hide yes)
			(effects
				(font
					(size 1.016 1.016)
					(thickness 0.1524)
				)
				(justify mirror)
			)
		)
		(duplicate_pad_numbers_are_jumpers no)
		(fp_line
			(start 2.286 4.8768)
			(end 2.286 2.032)
			(stroke
				(width 0.1524)
				(type default)
			)
			(layer "B.SilkS")
		)
		(fp_line
			(start 2.286 -4.8768)
			(end 2.286 -2.032)
			(stroke
				(width 0.1524)
				(type default)
			)
			(layer "B.SilkS")
		)
		(fp_line
			(start -2.1082 -4.699)
			(end 2.1082 -4.699)
			(stroke
				(width 0.508)
				(type default)
			)
			(layer "B.SilkS")
		)
		(fp_line
			(start -2.286 4.8768)
			(end 2.286 4.8768)
			(stroke
				(width 0.1524)
				(type default)
			)
			(layer "B.SilkS")
		)
		(fp_line
			(start -2.286 2.032)
			(end -2.286 4.8768)
			(stroke
				(width 0.1524)
				(type default)
			)
			(layer "B.SilkS")
		)
		(fp_line
			(start -2.286 -2.032)
			(end -2.286 -4.8768)
			(stroke
				(width 0.1524)
				(type default)
			)
			(layer "B.SilkS")
		)
		(fp_line
			(start -2.286 -4.8768)
			(end 2.286 -4.8768)
			(stroke
				(width 0.1524)
				(type default)
			)
			(layer "B.SilkS")
		)
		(fp_rect
			(start 2.1463 3.6449)
			(end -2.1463 -3.6449)
			(stroke
				(width 0)
				(type default)
			)
			(fill no)
			(layer "B.CrtYd")
		)
		(fp_poly
			(pts
				(xy 2.54 4.953) (xy 2.54 4.2926) (xy 3.81 4.2926) (xy 3.81 -4.2926) (xy 2.54 -4.2926) (xy 2.54 -4.953)
				(xy -2.54 -4.953) (xy -2.54 -4.2926) (xy -3.81 -4.2926) (xy -3.81 -1.6256) (xy -2.1463 -1.6256)
				(xy -2.1463 -3.6449) (xy 2.1463 -3.6449) (xy 2.1463 3.6449) (xy -2.1463 3.6449) (xy -2.1463 -1.6129)
				(xy -3.81 -1.6129) (xy -3.81 4.2926) (xy -2.54 4.2926) (xy -2.54 4.953)
			)
			(stroke
				(width 0)
				(type default)
			)
			(fill no)
			(layer "B.CrtYd")
		)
		(fp_rect
			(start 3.81 4.2926)
			(end 2.54 -4.2926)
			(stroke
				(width 0)
				(type default)
			)
			(fill no)
			(layer "B.Fab")
		)
		(fp_rect
			(start 2.54 4.953)
			(end -2.54 -4.953)
			(stroke
				(width 0)
				(type default)
			)
			(fill no)
			(layer "B.Fab")
		)
		(fp_rect
			(start -2.54 4.2926)
			(end -3.81 -4.2926)
			(stroke
				(width 0)
				(type default)
			)
			(fill no)
			(layer "B.Fab")
		)
		(pad "1" smd rect
			(at 0 -3.1496)
			(size 2.413 2.286)
			(layers "B.Cu" "B.Mask" "B.Paste")
			(net "P5V_A_1")
		)
		(pad "2" smd rect
			(at 0 3.1496)
			(size 2.413 2.286)
			(layers "B.Cu" "B.Mask" "B.Paste")
			(net "GND")
		)
		(zone
			(layer "B.Cu")
			(hatch none 0.5)
			(connect_pads
				(clearance 0)
			)
			(min_thickness 0.25)
			(keepout
				(tracks allowed)
				(vias not_allowed)
				(pads allowed)
				(copperpour not_allowed)
				(footprints allowed)
			)
			(placement
				(enabled no)
				(sheetname "")
			)
			(fill
				(thermal_gap 0.5)
				(thermal_bridge_width 0.5)
				(island_removal_mode 0)
			)
			(polygon
				(pts
					(xy 47.1043 -258.5466) (xy 50.1269 -258.5466) (xy 50.1269 -255.651) (xy 50.1269 -255.3208) (xy 47.1043 -255.3208)
					(xy 47.1043 -255.651)
				)
			)
		)
		(zone
			(layer "B.Cu")
			(hatch none 0.5)
			(connect_pads
				(clearance 0)
			)
			(min_thickness 0.25)
			(keepout
				(tracks allowed)
				(vias not_allowed)
				(pads allowed)
				(copperpour not_allowed)
				(footprints allowed)
			)
			(placement
				(enabled no)
				(sheetname "")
			)
			(fill
				(thermal_gap 0.5)
				(thermal_bridge_width 0.5)
				(island_removal_mode 0)
			)
			(polygon
				(pts
					(xy 50.1269 -252.2601) (xy 50.1269 -249.3518) (xy 47.1043 -249.3518) (xy 47.1043 -252.2474) (xy 47.1043 -252.5776)
					(xy 50.1269 -252.5776)
				)
			)
		)
	)
)
